(kicad_pcb
	(version 20241229)
	(generator "pcbnew")
	(generator_version "9.0")
	(general
		(thickness 1.62)
		(legacy_teardrops no)
	)
	(paper "A4")
	(title_block
		(title "OCuLink to 10GbE adapter")
		(date "2026-02-23")
		(rev "1.1.0")
		(company "Antmicro Ltd")
		(comment 1 "www.antmicro.com")
		(comment 9 "footprints 42-47 of 510")
	)
	(layers
		(0 "F.Cu" signal)
		(4 "In1.Cu" signal)
		(6 "In2.Cu" signal)
		(8 "In3.Cu" signal)
		(10 "In4.Cu" signal)
		(12 "In5.Cu" signal)
		(14 "In6.Cu" signal)
		(2 "B.Cu" signal)
		(9 "F.Adhes" user "F.Adhesive")
		(11 "B.Adhes" user "B.Adhesive")
		(13 "F.Paste" user)
		(15 "B.Paste" user)
		(5 "F.SilkS" user "F.Silkscreen")
		(7 "B.SilkS" user "B.Silkscreen")
		(1 "F.Mask" user)
		(3 "B.Mask" user)
		(17 "Dwgs.User" user "User.Drawings")
		(19 "Cmts.User" user "User.Comments")
		(21 "Eco1.User" user "User.Eco1")
		(23 "Eco2.User" user "User.Eco2")
		(25 "Edge.Cuts" user)
		(27 "Margin" user)
		(31 "F.CrtYd" user "F.Courtyard")
		(29 "B.CrtYd" user "B.Courtyard")
		(35 "F.Fab" user)
		(33 "B.Fab" user)
	)
	(footprint "antmicro-footprints:R_0402_1005Metric"
		(layer "F.Cu")
		(at 99.349999 109.1 180)
		(descr "Resistor SMD 0402")
		(tags "resistor SMD 0402")
		(property "Reference" "R44"
			(at 1.249999 -15.7 0)
			(layer "F.SilkS")
			(effects
				(font
					(size 0.7 0.7)
					(thickness 0.15)
				)
				(justify left bottom)
			)
		)
		(property "Value" "R_22R_0402"
			(at -1.011843 1.772046 0)
			(layer "F.Fab")
			(hide yes)
			(effects
				(font
					(size 0.7 0.7)
					(thickness 0.15)
				)
				(justify right top)
			)
		)
		(property "Datasheet" "https://www.bourns.com/docs/product-datasheets/cr.pdf"
			(at 0 0 0)
			(layer "F.Fab")
			(hide yes)
			(effects
				(font
					(size 1.27 1.27)
					(thickness 0.15)
				)
			)
		)
		(property "Description" "SMD Chip Resistor, 22 ohm, ± 1%, 62.5 mW, 0402 [1005 Metric], Thick Film, General Purpose"
			(at 0 0 0)
			(layer "F.Fab")
			(hide yes)
			(effects
				(font
					(size 1.27 1.27)
					(thickness 0.15)
				)
			)
		)
		(property "MPN" "CR0402-FX-22R0GLF"
			(at 0 0 180)
			(unlocked yes)
			(layer "F.Fab")
			(hide yes)
			(effects
				(font
					(size 1 1)
					(thickness 0.15)
				)
			)
		)
		(property "Manufacturer" "Bourns"
			(at 0 0 180)
			(unlocked yes)
			(layer "F.Fab")
			(hide yes)
			(effects
				(font
					(size 1 1)
					(thickness 0.15)
				)
			)
		)
		(property "License" "Apache-2.0"
			(at 0 0 180)
			(unlocked yes)
			(layer "F.Fab")
			(hide yes)
			(effects
				(font
					(size 1 1)
					(thickness 0.15)
				)
			)
		)
		(property "Author" "Antmicro"
			(at 0 0 180)
			(unlocked yes)
			(layer "F.Fab")
			(hide yes)
			(effects
				(font
					(size 1 1)
					(thickness 0.15)
				)
			)
		)
		(property "Val" "22R"
			(at 0 0 180)
			(unlocked yes)
			(layer "F.Fab")
			(hide yes)
			(effects
				(font
					(size 1 1)
					(thickness 0.15)
				)
			)
		)
		(property "Tolerance" "1%"
			(at 0 0 180)
			(unlocked yes)
			(layer "F.Fab")
			(hide yes)
			(effects
				(font
					(size 1 1)
					(thickness 0.15)
				)
			)
		)
		(sheetname "/X710-AT2 10GbE/")
		(sheetfile "x710-at2-10gbe.kicad_sch")
		(attr smd)
		(fp_rect
			(start -0.925 -0.47)
			(end 0.925 0.47)
			(stroke
				(width 0.05)
				(type default)
			)
			(fill no)
			(layer "F.CrtYd")
		)
		(fp_rect
			(start -0.5 -0.25)
			(end 0.5 0.25)
			(stroke
				(width 0.15)
				(type solid)
			)
			(fill no)
			(layer "F.Fab")
		)
		(pad "1" smd roundrect
			(at -0.48 0 180)
			(size 0.59 0.64)
			(layers "F.Cu" "F.Mask" "F.Paste")
			(roundrect_rratio 0.25)
			(net 150 "/X710-AT2 10GbE/25MHZ_OSC_R.-")
			(pintype "passive")
		)
		(pad "2" smd roundrect
			(at 0.48 0 180)
			(size 0.59 0.64)
			(layers "F.Cu" "F.Mask" "F.Paste")
			(roundrect_rratio 0.25)
			(net 73 "/X710-AT2 10GbE/25MHZ_OSC_AC.-")
			(pintype "passive")
		)
	)
	(footprint "antmicro-footprints:R_0402_1005Metric"
		(layer "F.Cu")
		(at 99.35 106.15 180)
		(descr "Resistor SMD 0402")
		(tags "resistor SMD 0402")
		(property "Reference" "R82"
			(at 1.25 -15.425 0)
			(layer "F.SilkS")
			(effects
				(font
					(size 0.7 0.7)
					(thickness 0.15)
				)
				(justify left bottom)
			)
		)
		(property "Value" "R_100k_0402"
			(at -1.011843 1.772046 0)
			(layer "F.Fab")
			(hide yes)
			(effects
				(font
					(size 0.7 0.7)
					(thickness 0.15)
				)
				(justify right top)
			)
		)
		(property "Datasheet" "https://www.bourns.com/docs/product-datasheets/cr.pdf"
			(at 0 0 0)
			(layer "F.Fab")
			(hide yes)
			(effects
				(font
					(size 1.27 1.27)
					(thickness 0.15)
				)
			)
		)
		(property "Description" "SMD Chip Resistor, 100 kohm, ± 1%, 62.5 mW, 0402 [1005 Metric], Thick Film, General Purpose"
			(at 0 0 0)
			(layer "F.Fab")
			(hide yes)
			(effects
				(font
					(size 1.27 1.27)
					(thickness 0.15)
				)
			)
		)
		(property "MPN" "CR0402-FX-1003GLF"
			(at 0 0 180)
			(unlocked yes)
			(layer "F.Fab")
			(hide yes)
			(effects
				(font
					(size 1 1)
					(thickness 0.15)
				)
			)
		)
		(property "Manufacturer" "Bourns"
			(at 0 0 180)
			(unlocked yes)
			(layer "F.Fab")
			(hide yes)
			(effects
				(font
					(size 1 1)
					(thickness 0.15)
				)
			)
		)
		(property "License" "Apache-2.0"
			(at 0 0 180)
			(unlocked yes)
			(layer "F.Fab")
			(hide yes)
			(effects
				(font
					(size 1 1)
					(thickness 0.15)
				)
			)
		)
		(property "Author" "Antmicro"
			(at 0 0 180)
			(unlocked yes)
			(layer "F.Fab")
			(hide yes)
			(effects
				(font
					(size 1 1)
					(thickness 0.15)
				)
			)
		)
		(property "Val" "100k"
			(at 0 0 180)
			(unlocked yes)
			(layer "F.Fab")
			(hide yes)
			(effects
				(font
					(size 1 1)
					(thickness 0.15)
				)
			)
		)
		(property "Tolerance" "1%"
			(at 0 0 180)
			(unlocked yes)
			(layer "F.Fab")
			(hide yes)
			(effects
				(font
					(size 1 1)
					(thickness 0.15)
				)
			)
		)
		(sheetname "/X710-AT2 Misc/")
		(sheetfile "x710-at2-mics.kicad_sch")
		(attr smd exclude_from_pos_files exclude_from_bom dnp)
		(fp_rect
			(start -0.925 -0.47)
			(end 0.925 0.47)
			(stroke
				(width 0.05)
				(type default)
			)
			(fill no)
			(layer "F.CrtYd")
		)
		(fp_rect
			(start -0.5 -0.25)
			(end 0.5 0.25)
			(stroke
				(width 0.15)
				(type solid)
			)
			(fill no)
			(layer "F.Fab")
		)
		(pad "1" smd roundrect
			(at -0.48 0 180)
			(size 0.59 0.64)
			(layers "F.Cu" "F.Mask" "F.Paste")
			(roundrect_rratio 0.25)
			(net 364 "/X710-AT2 Misc/NCSI.ARB_OUT")
			(pintype "passive")
		)
		(pad "2" smd roundrect
			(at 0.48 0 180)
			(size 0.59 0.64)
			(layers "F.Cu" "F.Mask" "F.Paste")
			(roundrect_rratio 0.25)
			(net 7 "+3V3")
			(pintype "passive")
		)
	)
	(footprint "antmicro-footprints:R_0402_1005Metric"
		(layer "F.Cu")
		(at 110.35 93.45 -90)
		(descr "Resistor SMD 0402")
		(tags "resistor SMD 0402")
		(property "Reference" "R67"
			(at -3.85 -0.35 90)
			(layer "F.SilkS")
			(effects
				(font
					(size 0.7 0.7)
					(thickness 0.15)
				)
				(justify left bottom)
			)
		)
		(property "Value" "R_10R_0402"
			(at -1.011843 1.772046 90)
			(layer "F.Fab")
			(hide yes)
			(effects
				(font
					(size 0.7 0.7)
					(thickness 0.15)
				)
				(justify right top)
			)
		)
		(property "Datasheet" "https://www.bourns.com/docs/product-datasheets/cr.pdf"
			(at 0 0 90)
			(layer "F.Fab")
			(hide yes)
			(effects
				(font
					(size 1.27 1.27)
					(thickness 0.15)
				)
			)
		)
		(property "Description" "SMD Chip Resistor, 10 ohm, ± 1%, 62.5 mW, 0402 [1005 Metric], Thick Film, General Purpose"
			(at 0 0 90)
			(layer "F.Fab")
			(hide yes)
			(effects
				(font
					(size 1.27 1.27)
					(thickness 0.15)
				)
			)
		)
		(property "MPN" "CR0402-FX-10R0GLF"
			(at 0 0 270)
			(unlocked yes)
			(layer "F.Fab")
			(hide yes)
			(effects
				(font
					(size 1 1)
					(thickness 0.15)
				)
			)
		)
		(property "Manufacturer" "Bourns"
			(at 0 0 270)
			(unlocked yes)
			(layer "F.Fab")
			(hide yes)
			(effects
				(font
					(size 1 1)
					(thickness 0.15)
				)
			)
		)
		(property "License" "Apache-2.0"
			(at 0 0 270)
			(unlocked yes)
			(layer "F.Fab")
			(hide yes)
			(effects
				(font
					(size 1 1)
					(thickness 0.15)
				)
			)
		)
		(property "Author" "Antmicro"
			(at 0 0 270)
			(unlocked yes)
			(layer "F.Fab")
			(hide yes)
			(effects
				(font
					(size 1 1)
					(thickness 0.15)
				)
			)
		)
		(property "Val" "10R"
			(at 0 0 270)
			(unlocked yes)
			(layer "F.Fab")
			(hide yes)
			(effects
				(font
					(size 1 1)
					(thickness 0.15)
				)
			)
		)
		(property "Tolerance" "1%"
			(at 0 0 270)
			(unlocked yes)
			(layer "F.Fab")
			(hide yes)
			(effects
				(font
					(size 1 1)
					(thickness 0.15)
				)
			)
		)
		(sheetname "/X710-AT2 10GbE/")
		(sheetfile "x710-at2-10gbe.kicad_sch")
		(attr smd)
		(fp_rect
			(start -0.925 -0.47)
			(end 0.925 0.47)
			(stroke
				(width 0.05)
				(type default)
			)
			(fill no)
			(layer "F.CrtYd")
		)
		(fp_rect
			(start -0.5 -0.25)
			(end 0.5 0.25)
			(stroke
				(width 0.15)
				(type solid)
			)
			(fill no)
			(layer "F.Fab")
		)
		(pad "1" smd roundrect
			(at -0.48 0 270)
			(size 0.59 0.64)
			(layers "F.Cu" "F.Mask" "F.Paste")
			(roundrect_rratio 0.25)
			(net 215 "/X710-AT2 10GbE/MDIO0_I2C0.MDIO")
			(pintype "passive")
		)
		(pad "2" smd roundrect
			(at 0.48 0 270)
			(size 0.59 0.64)
			(layers "F.Cu" "F.Mask" "F.Paste")
			(roundrect_rratio 0.25)
			(net 132 "/X710-AT2 10GbE/MDIO0_SDA0")
			(pintype "passive")
		)
	)
	(footprint "antmicro-footprints:R_0402_1005Metric"
		(layer "F.Cu")
		(at 99.35 104.25 180)
		(descr "Resistor SMD 0402")
		(tags "resistor SMD 0402")
		(property "Reference" "R78"
			(at 1.25 -15.175 0)
			(layer "F.SilkS")
			(effects
				(font
					(size 0.7 0.7)
					(thickness 0.15)
				)
				(justify left bottom)
			)
		)
		(property "Value" "R_100k_0402"
			(at -1.011843 1.772046 0)
			(layer "F.Fab")
			(hide yes)
			(effects
				(font
					(size 0.7 0.7)
					(thickness 0.15)
				)
				(justify right top)
			)
		)
		(property "Datasheet" "https://www.bourns.com/docs/product-datasheets/cr.pdf"
			(at 0 0 0)
			(layer "F.Fab")
			(hide yes)
			(effects
				(font
					(size 1.27 1.27)
					(thickness 0.15)
				)
			)
		)
		(property "Description" "SMD Chip Resistor, 100 kohm, ± 1%, 62.5 mW, 0402 [1005 Metric], Thick Film, General Purpose"
			(at 0 0 0)
			(layer "F.Fab")
			(hide yes)
			(effects
				(font
					(size 1.27 1.27)
					(thickness 0.15)
				)
			)
		)
		(property "MPN" "CR0402-FX-1003GLF"
			(at 0 0 180)
			(unlocked yes)
			(layer "F.Fab")
			(hide yes)
			(effects
				(font
					(size 1 1)
					(thickness 0.15)
				)
			)
		)
		(property "Manufacturer" "Bourns"
			(at 0 0 180)
			(unlocked yes)
			(layer "F.Fab")
			(hide yes)
			(effects
				(font
					(size 1 1)
					(thickness 0.15)
				)
			)
		)
		(property "License" "Apache-2.0"
			(at 0 0 180)
			(unlocked yes)
			(layer "F.Fab")
			(hide yes)
			(effects
				(font
					(size 1 1)
					(thickness 0.15)
				)
			)
		)
		(property "Author" "Antmicro"
			(at 0 0 180)
			(unlocked yes)
			(layer "F.Fab")
			(hide yes)
			(effects
				(font
					(size 1 1)
					(thickness 0.15)
				)
			)
		)
		(property "Val" "100k"
			(at 0 0 180)
			(unlocked yes)
			(layer "F.Fab")
			(hide yes)
			(effects
				(font
					(size 1 1)
					(thickness 0.15)
				)
			)
		)
		(property "Tolerance" "1%"
			(at 0 0 180)
			(unlocked yes)
			(layer "F.Fab")
			(hide yes)
			(effects
				(font
					(size 1 1)
					(thickness 0.15)
				)
			)
		)
		(sheetname "/X710-AT2 Misc/")
		(sheetfile "x710-at2-mics.kicad_sch")
		(attr smd)
		(fp_rect
			(start -0.925 -0.47)
			(end 0.925 0.47)
			(stroke
				(width 0.05)
				(type default)
			)
			(fill no)
			(layer "F.CrtYd")
		)
		(fp_rect
			(start -0.5 -0.25)
			(end 0.5 0.25)
			(stroke
				(width 0.15)
				(type solid)
			)
			(fill no)
			(layer "F.Fab")
		)
		(pad "1" smd roundrect
			(at -0.48 0 180)
			(size 0.59 0.64)
			(layers "F.Cu" "F.Mask" "F.Paste")
			(roundrect_rratio 0.25)
			(net 360 "/X710-AT2 Misc/NCSI.RXD_1")
			(pintype "passive")
		)
		(pad "2" smd roundrect
			(at 0.48 0 180)
			(size 0.59 0.64)
			(layers "F.Cu" "F.Mask" "F.Paste")
			(roundrect_rratio 0.25)
			(net 7 "+3V3")
			(pintype "passive")
		)
	)
	(footprint "antmicro-footprints:Vishay_PowerPAK_1212-8_Single"
		(layer "F.Cu")
		(at 66.76 66 90)
		(descr "PowerPAK 1212-8 Single")
		(tags "Vishay PowerPAK 1212-8 Single")
		(property "Reference" "Q2"
			(at -1.75 -1.86 90)
			(layer "F.SilkS")
			(effects
				(font
					(size 0.7 0.7)
					(thickness 0.15)
				)
				(justify left bottom)
			)
		)
		(property "Value" "SQS401EN-T1_BE3"
			(at 0 2.7 90)
			(layer "F.Fab")
			(hide yes)
			(effects
				(font
					(size 0.7 0.7)
					(thickness 0.15)
				)
				(justify left bottom)
			)
		)
		(property "Datasheet" "https://www.vishay.com/docs/65529/sqs401en.pdf"
			(at 0 0 90)
			(layer "F.Fab")
			(hide yes)
			(effects
				(font
					(size 1.27 1.27)
					(thickness 0.15)
				)
			)
		)
		(property "Description" "MOSFET, P Channel, 40 V, 16A, 0.047 ohm, PowerPAK 1212-8, Surface Mount"
			(at 0 0 90)
			(layer "F.Fab")
			(hide yes)
			(effects
				(font
					(size 1.27 1.27)
					(thickness 0.15)
				)
			)
		)
		(property "MPN" "SQS401EN-T1_BE3"
			(at 0 0 90)
			(unlocked yes)
			(layer "F.Fab")
			(hide yes)
			(effects
				(font
					(size 1 1)
					(thickness 0.15)
				)
			)
		)
		(property "Manufacturer" "Vishay"
			(at 0 0 90)
			(unlocked yes)
			(layer "F.Fab")
			(hide yes)
			(effects
				(font
					(size 1 1)
					(thickness 0.15)
				)
			)
		)
		(property "Author" "Antmicro"
			(at 0 0 90)
			(unlocked yes)
			(layer "F.Fab")
			(hide yes)
			(effects
				(font
					(size 1 1)
					(thickness 0.15)
				)
			)
		)
		(property "License" "Apache-2.0"
			(at 0 0 90)
			(unlocked yes)
			(layer "F.Fab")
			(hide yes)
			(effects
				(font
					(size 1 1)
					(thickness 0.15)
				)
			)
		)
		(sheetname "/Power/Ideal diode 1/")
		(sheetfile "ideal-diode.kicad_sch")
		(attr smd)
		(fp_line
			(start 1.648 -1.651)
			(end 1.648 -1.317)
			(stroke
				(width 0.15)
				(type solid)
			)
			(layer "F.SilkS")
		)
		(fp_line
			(start -1.651 -1.651)
			(end 1.648 -1.651)
			(stroke
				(width 0.15)
				(type solid)
			)
			(layer "F.SilkS")
		)
		(fp_line
			(start -1.651 -1.651)
			(end -1.651 -1.317)
			(stroke
				(width 0.15)
				(type solid)
			)
			(layer "F.SilkS")
		)
		(fp_line
			(start 1.634 1.3)
			(end 1.634 1.634)
			(stroke
				(width 0.15)
				(type solid)
			)
			(layer "F.SilkS")
		)
		(fp_line
			(start -1.635 1.3)
			(end -1.635 1.634)
			(stroke
				(width 0.15)
				(type solid)
			)
			(layer "F.SilkS")
		)
		(fp_line
			(start -1.635 1.634)
			(end 1.634 1.634)
			(stroke
				(width 0.15)
				(type solid)
			)
			(layer "F.SilkS")
		)
		(fp_circle
			(center -1.9 -1.4)
			(end -1.85 -1.4)
			(stroke
				(width 0.15)
				(type solid)
			)
			(fill yes)
			(layer "F.SilkS")
		)
		(fp_rect
			(start -2 -1.8)
			(end 2 1.798)
			(stroke
				(width 0.05)
				(type solid)
			)
			(fill no)
			(layer "F.CrtYd")
		)
		(fp_line
			(start -1.6425 -1.4175)
			(end -1.4175 -1.6425)
			(stroke
				(width 0.15)
				(type solid)
			)
			(layer "F.Fab")
		)
		(fp_rect
			(start -1.651 -1.651)
			(end 1.648 1.648)
			(stroke
				(width 0.15)
				(type solid)
			)
			(fill no)
			(layer "F.Fab")
		)
		(pad "1" smd rect
			(at -1.436 -0.99 90)
			(size 0.99 0.405)
			(layers "F.Cu" "F.Mask" "F.Paste")
			(net 314 "VCC")
			(pinfunction "S")
			(pintype "passive")
		)
		(pad "2" smd rect
			(at -1.436 -0.332 90)
			(size 0.99 0.405)
			(layers "F.Cu" "F.Mask" "F.Paste")
			(net 314 "VCC")
			(pinfunction "S")
			(pintype "passive")
		)
		(pad "3" smd rect
			(at -1.436 0.33 90)
			(size 0.99 0.405)
			(layers "F.Cu" "F.Mask" "F.Paste")
			(net 314 "VCC")
			(pinfunction "S")
			(pintype "passive")
		)
		(pad "4" smd rect
			(at -1.436 0.988 90)
			(size 0.99 0.405)
			(layers "F.Cu" "F.Mask" "F.Paste")
			(net 373 "Net-(Q2-G)")
			(pinfunction "G")
			(pintype "passive")
		)
		(pad "5" smd custom
			(at 0.557 0 90)
			(size 1.725 2.235)
			(layers "F.Cu" "F.Mask" "F.Paste")
			(net 350 "/Power/+12V_IN")
			(pinfunction "D")
			(pintype "passive")
			(zone_connect 2)
			(options
				(clearance outline)
				(anchor rect)
			)
			(primitives
				(gr_poly
					(pts
						(xy 0.8625 0.1275) (xy 0.8625 -0.1275) (xy 1.3725 -0.1275) (xy 1.3725 -0.5325) (xy 0.8625 -0.5325)
						(xy 0.8625 -0.7875) (xy 1.3725 -0.7875) (xy 1.3725 -1.195) (xy 0.6125 -1.195) (xy 0.6125 1.195)
						(xy 1.3725 1.195) (xy 1.3725 0.7875) (xy 0.8625 0.7875) (xy 0.8625 0.5325) (xy 1.3725 0.5325)
						(xy 1.3725 0.1275)
					)
					(width 0)
					(fill yes)
				)
			)
		)
	)
	(footprint "antmicro-footprints:R_0402_1005Metric"
		(layer "F.Cu")
		(at 90.1 112.45 90)
		(descr "Resistor SMD 0402")
		(tags "resistor SMD 0402")
		(property "Reference" "R69"
			(at -0.85 0.475 90)
			(layer "F.SilkS")
			(effects
				(font
					(size 0.7 0.7)
					(thickness 0.15)
				)
				(justify right bottom)
			)
		)
		(property "Value" "R_0R_0402"
			(at -1.011843 1.772046 90)
			(layer "F.Fab")
			(hide yes)
			(effects
				(font
					(size 0.7 0.7)
					(thickness 0.15)
				)
				(justify left bottom)
			)
		)
		(property "Datasheet" "https://industrial.panasonic.com/cdbs/www-data/pdf/RDA0000/AOA0000C301.pdf"
			(at 0 0 90)
			(layer "F.Fab")
			(hide yes)
			(effects
				(font
					(size 1.27 1.27)
					(thickness 0.15)
				)
			)
		)
		(property "Description" "SMD Chip Resistor, Jumper, 0 ohm, 100 mW, 0402 [1005 Metric], Thick Film, General Purpose"
			(at 0 0 90)
			(layer "F.Fab")
			(hide yes)
			(effects
				(font
					(size 1.27 1.27)
					(thickness 0.15)
				)
			)
		)
		(property "MPN" "ERJ2GE0R00X"
			(at 0 0 90)
			(unlocked yes)
			(layer "F.Fab")
			(hide yes)
			(effects
				(font
					(size 1 1)
					(thickness 0.15)
				)
			)
		)
		(property "Manufacturer" "Panasonic"
			(at 0 0 90)
			(unlocked yes)
			(layer "F.Fab")
			(hide yes)
			(effects
				(font
					(size 1 1)
					(thickness 0.15)
				)
			)
		)
		(property "License" "Apache-2.0"
			(at 0 0 90)
			(unlocked yes)
			(layer "F.Fab")
			(hide yes)
			(effects
				(font
					(size 1 1)
					(thickness 0.15)
				)
			)
		)
		(property "Author" "Antmicro"
			(at 0 0 90)
			(unlocked yes)
			(layer "F.Fab")
			(hide yes)
			(effects
				(font
					(size 1 1)
					(thickness 0.15)
				)
			)
		)
		(property "Val" "0R"
			(at 0 0 90)
			(unlocked yes)
			(layer "F.Fab")
			(hide yes)
			(effects
				(font
					(size 1 1)
					(thickness 0.15)
				)
			)
		)
		(property "Tolerance" "~"
			(at 0 0 90)
			(unlocked yes)
			(layer "F.Fab")
			(hide yes)
			(effects
				(font
					(size 1 1)
					(thickness 0.15)
				)
			)
		)
		(property "Current" "1A"
			(at 0 0 90)
			(unlocked yes)
			(layer "F.Fab")
			(hide yes)
			(effects
				(font
					(size 1 1)
					(thickness 0.15)
				)
			)
		)
		(sheetname "/X710-AT2 10GbE/")
		(sheetfile "x710-at2-10gbe.kicad_sch")
		(attr smd)
		(fp_rect
			(start -0.925 -0.47)
			(end 0.925 0.47)
			(stroke
				(width 0.05)
				(type default)
			)
			(fill no)
			(layer "F.CrtYd")
		)
		(fp_rect
			(start -0.5 -0.25)
			(end 0.5 0.25)
			(stroke
				(width 0.15)
				(type solid)
			)
			(fill no)
			(layer "F.Fab")
		)
		(pad "1" smd roundrect
			(at -0.48 0 90)
			(size 0.59 0.64)
			(layers "F.Cu" "F.Mask" "F.Paste")
			(roundrect_rratio 0.25)
			(net 380 "/X710-AT2 10GbE/~{PHY_RESET_3V3}")
			(pintype "passive")
		)
		(pad "2" smd roundrect
			(at 0.48 0 90)
			(size 0.59 0.64)
			(layers "F.Cu" "F.Mask" "F.Paste")
			(roundrect_rratio 0.25)
			(net 141 "/X710-AT2 10GbE/~{PHY_RESET_3V3_R}")
			(pintype "passive")
		)
	)
)
